#ISCELL
  mstr_misc dns *
  *
#ISCELL
  pure_quanta quanta_title_block_c *
  *
#CELL
  pure_quanta q_res *
  page127_i1
#ISCELL
  standard offpage *
  page127_i10
#ISCELL
  standard offpage *
  page127_i11
#ISCELL
  standard offpage *
  page127_i12
#CELL
  pure_quanta q_res *
  page127_i13
#CELL
  pure_quanta q_res *
  page127_i14
#CELL
  pure_quanta q_res *
  page127_i15
#ISCELL
  logical_power universal_gnd *
  page127_i16
#CELL
  pure_quanta q_res *
  page127_i17
#ISCELL
  logical_power universal_gnd *
  page127_i18
#ISCELL
  logical_power universal_power *
  page127_i19
#ISCELL
  standard offpage *
  page127_i2
#CELL
  pure_quanta q_res *
  page127_i20
#CELL
  pure_quanta q_res *
  page127_i21
#ISCELL
  logical_power universal_gnd *
  page127_i22
#ISCELL
  logical_power universal_power *
  page127_i23
#CELL
  pure_quanta q_res *
  page127_i24
#ISCELL
  logical_power universal_gnd *
  page127_i25
#CELL
  pure_quanta q_res *
  page127_i26
#ISCELL
  standard offpage *
  page127_i27
#ISCELL
  logical_power universal_power *
  page127_i28
#ISCELL
  standard offpage *
  page127_i3
#ISCELL
  logical_power universal_gnd *
  page127_i30
#CELL
  pure_quanta q_res *
  page127_i31
#CELL
  pure_quanta q_res *
  page127_i32
#ISCELL
  standard offpage *
  page127_i33
#ISCELL
  logical_power universal_power *
  page127_i34
#CELL
  pure_quanta q_res *
  page127_i35
#CELL
  pure_quanta q_res *
  page127_i36
#ISCELL
  logical_power universal_gnd *
  page127_i37
#ISCELL
  standard offpage *
  page127_i4
#CELL
  pure_quanta q_res *
  page127_i5
#CELL
  pure_quanta q_res *
  page127_i6
#CELL
  pure_quanta q_res *
  page127_i7
#ISCELL
  logical_power universal_gnd *
  page127_i8
#ISCELL
  logical_power universal_gnd *
  page127_i9
